(kicad_pcb
	(version 20260206)
	(generator "pcbnew")
	(generator_version "10.0")
	(general
		(thickness 1.6)
		(legacy_teardrops no)
	)
	(paper "A4")
	(title_block
		(title "04192023_DAF0TMB3IC0_F0TG_MB_C_brd_V02_OCP.brd")
		(comment 1 "Grand Teton / footprints 7805-7811 of 8354")
	)
	(layers
		(0 "F.Cu" signal "TOP")
		(4 "In1.Cu" signal "GND")
		(6 "In2.Cu" signal "IN1")
		(8 "In3.Cu" signal "GND1")
		(10 "In4.Cu" signal "IN2")
		(12 "In5.Cu" signal "GND2")
		(14 "In6.Cu" signal "IN3")
		(16 "In7.Cu" signal "GND3")
		(18 "In8.Cu" signal "VCC")
		(20 "In9.Cu" signal "VCC1")
		(22 "In10.Cu" signal "GND4")
		(24 "In11.Cu" signal "IN4")
		(26 "In12.Cu" signal "GND5")
		(28 "In13.Cu" signal "IN5")
		(30 "In14.Cu" signal "GND6")
		(32 "In15.Cu" signal "IN6")
		(34 "In16.Cu" signal "GND7")
		(2 "B.Cu" signal "BOTTOM")
		(9 "F.Adhes" user "F.Adhesive")
		(11 "B.Adhes" user "B.Adhesive")
		(13 "F.Paste" user "Package Geometry/Pastemask Top")
		(15 "B.Paste" user "Package Geometry/Pastemask Bottom")
		(5 "F.SilkS" user "Ref Des/Silkscreen Top")
		(7 "B.SilkS" user "Ref Des/Silkscreen Bottom")
		(1 "F.Mask" user "Board Geometry/Soldermask Top")
		(3 "B.Mask" user "Board Geometry/Soldermask Bottom")
		(17 "Dwgs.User" user "User.Drawings")
		(19 "Cmts.User" user "User.Comments")
		(21 "Eco1.User" user "User.Eco1")
		(23 "Eco2.User" user "User.Eco2")
		(25 "Edge.Cuts" user "Board Geometry/Outline")
		(27 "Margin" user)
		(31 "F.CrtYd" user "Package Geometry/Place Bound Top")
		(29 "B.CrtYd" user "Package Geometry/Place Bound Bottom")
		(35 "F.Fab" user "Ref Des/Assembly Top")
		(33 "B.Fab" user "Ref Des/Assembly Bottom")
	)
	(footprint ""
		(layer "B.Cu")
		(at 121.944638 -263.465564)
		(property "Reference" "C2482"
			(at 0 0 0)
			(layer "B.SilkS")
			(hide yes)
			(effects
				(font
					(size 1.27 1.27)
				)
				(justify mirror)
			)
		)
		(property "Value" ""
			(at 0 0 0)
			(layer "B.Fab")
			(effects
				(font
					(size 1.27 1.27)
				)
				(justify mirror)
			)
		)
		(duplicate_pad_numbers_are_jumpers no)
		(fp_line
			(start -0.7874 -0.4064)
			(end -0.7874 0.4064)
			(stroke
				(width 0.1524)
				(type default)
			)
			(layer "B.SilkS")
		)
		(fp_line
			(start -0.7874 0.4064)
			(end 0.7874 0.4064)
			(stroke
				(width 0.1524)
				(type default)
			)
			(layer "B.SilkS")
		)
		(fp_line
			(start 0.7874 -0.4064)
			(end -0.7874 -0.4064)
			(stroke
				(width 0.1524)
				(type default)
			)
			(layer "B.SilkS")
		)
		(fp_line
			(start 0.7874 0.4064)
			(end 0.7874 -0.4064)
			(stroke
				(width 0.1524)
				(type default)
			)
			(layer "B.SilkS")
		)
		(fp_line
			(start -0.67945 -0.3048)
			(end -0.67945 0.3048)
			(stroke
				(width 0.1)
				(type default)
			)
			(layer "B.Fab")
		)
		(fp_line
			(start -0.67945 0.3048)
			(end -0.120396 0.3048)
			(stroke
				(width 0.1)
				(type default)
			)
			(layer "B.Fab")
		)
		(fp_line
			(start -0.12065 -0.3048)
			(end -0.67945 -0.3048)
			(stroke
				(width 0.1)
				(type default)
			)
			(layer "B.Fab")
		)
		(fp_line
			(start -0.12065 -0.2794)
			(end -0.12065 -0.3048)
			(stroke
				(width 0.1)
				(type default)
			)
			(layer "B.Fab")
		)
		(fp_line
			(start -0.120396 0.2794)
			(end 0.12065 0.2794)
			(stroke
				(width 0.1)
				(type default)
			)
			(layer "B.Fab")
		)
		(fp_line
			(start -0.120396 0.3048)
			(end -0.120396 0.2794)
			(stroke
				(width 0.1)
				(type default)
			)
			(layer "B.Fab")
		)
		(fp_line
			(start 0.12065 -0.305054)
			(end 0.12065 -0.2794)
			(stroke
				(width 0.1)
				(type default)
			)
			(layer "B.Fab")
		)
		(fp_line
			(start 0.12065 -0.2794)
			(end -0.12065 -0.2794)
			(stroke
				(width 0.1)
				(type default)
			)
			(layer "B.Fab")
		)
		(fp_line
			(start 0.12065 0.2794)
			(end 0.12065 0.3048)
			(stroke
				(width 0.1)
				(type default)
			)
			(layer "B.Fab")
		)
		(fp_line
			(start 0.12065 0.3048)
			(end 0.67945 0.3048)
			(stroke
				(width 0.1)
				(type default)
			)
			(layer "B.Fab")
		)
		(fp_line
			(start 0.67945 -0.305054)
			(end 0.12065 -0.305054)
			(stroke
				(width 0.1)
				(type default)
			)
			(layer "B.Fab")
		)
		(fp_line
			(start 0.67945 0.3048)
			(end 0.67945 -0.305054)
			(stroke
				(width 0.1)
				(type default)
			)
			(layer "B.Fab")
		)
		(pad "1" smd circle
			(at 0.40005 0 180)
			(size 0 0)
			(layers "B.Cu" "B.Mask" "B.Paste")
			(net "PVDD11_S3_P1")
		)
		(pad "2" smd circle
			(at -0.40005 0 180)
			(size 0 0)
			(layers "B.Cu" "B.Mask" "B.Paste")
			(net "GND")
		)
	)
	(footprint ""
		(layer "B.Cu")
		(at 349.320358 -248.47931 180)
		(property "Reference" "C4178"
			(at 0 0 0)
			(layer "B.SilkS")
			(hide yes)
			(effects
				(font
					(size 1.27 1.27)
				)
				(justify mirror)
			)
		)
		(property "Value" ""
			(at 0 0 0)
			(layer "B.Fab")
			(effects
				(font
					(size 1.27 1.27)
				)
				(justify mirror)
			)
		)
		(duplicate_pad_numbers_are_jumpers no)
		(fp_line
			(start 0.7874 0.4064)
			(end 0.7874 -0.4064)
			(stroke
				(width 0.1524)
				(type default)
			)
			(layer "B.SilkS")
		)
		(fp_line
			(start 0.7874 -0.4064)
			(end -0.7874 -0.4064)
			(stroke
				(width 0.1524)
				(type default)
			)
			(layer "B.SilkS")
		)
		(fp_line
			(start -0.7874 0.4064)
			(end 0.7874 0.4064)
			(stroke
				(width 0.1524)
				(type default)
			)
			(layer "B.SilkS")
		)
		(fp_line
			(start -0.7874 -0.4064)
			(end -0.7874 0.4064)
			(stroke
				(width 0.1524)
				(type default)
			)
			(layer "B.SilkS")
		)
		(fp_line
			(start 0.67945 0.3048)
			(end 0.67945 -0.305054)
			(stroke
				(width 0.1)
				(type default)
			)
			(layer "B.Fab")
		)
		(fp_line
			(start 0.67945 -0.305054)
			(end 0.12065 -0.305054)
			(stroke
				(width 0.1)
				(type default)
			)
			(layer "B.Fab")
		)
		(fp_line
			(start 0.12065 0.3048)
			(end 0.67945 0.3048)
			(stroke
				(width 0.1)
				(type default)
			)
			(layer "B.Fab")
		)
		(fp_line
			(start 0.12065 0.2794)
			(end 0.12065 0.3048)
			(stroke
				(width 0.1)
				(type default)
			)
			(layer "B.Fab")
		)
		(fp_line
			(start 0.12065 -0.2794)
			(end -0.12065 -0.2794)
			(stroke
				(width 0.1)
				(type default)
			)
			(layer "B.Fab")
		)
		(fp_line
			(start 0.12065 -0.305054)
			(end 0.12065 -0.2794)
			(stroke
				(width 0.1)
				(type default)
			)
			(layer "B.Fab")
		)
		(fp_line
			(start -0.120396 0.3048)
			(end -0.120396 0.2794)
			(stroke
				(width 0.1)
				(type default)
			)
			(layer "B.Fab")
		)
		(fp_line
			(start -0.120396 0.2794)
			(end 0.12065 0.2794)
			(stroke
				(width 0.1)
				(type default)
			)
			(layer "B.Fab")
		)
		(fp_line
			(start -0.12065 -0.2794)
			(end -0.12065 -0.3048)
			(stroke
				(width 0.1)
				(type default)
			)
			(layer "B.Fab")
		)
		(fp_line
			(start -0.12065 -0.3048)
			(end -0.67945 -0.3048)
			(stroke
				(width 0.1)
				(type default)
			)
			(layer "B.Fab")
		)
		(fp_line
			(start -0.67945 0.3048)
			(end -0.120396 0.3048)
			(stroke
				(width 0.1)
				(type default)
			)
			(layer "B.Fab")
		)
		(fp_line
			(start -0.67945 -0.3048)
			(end -0.67945 0.3048)
			(stroke
				(width 0.1)
				(type default)
			)
			(layer "B.Fab")
		)
		(pad "1" smd circle
			(at 0.40005 0)
			(size 0 0)
			(layers "B.Cu" "B.Mask" "B.Paste")
			(net "PVDDCR_CPU0_P0")
		)
		(pad "2" smd circle
			(at -0.40005 0)
			(size 0 0)
			(layers "B.Cu" "B.Mask" "B.Paste")
			(net "GND")
		)
	)
	(footprint ""
		(layer "B.Cu")
		(at 119.674386 -266.005564)
		(property "Reference" "C2481"
			(at 0 0 0)
			(layer "B.SilkS")
			(hide yes)
			(effects
				(font
					(size 1.27 1.27)
				)
				(justify mirror)
			)
		)
		(property "Value" ""
			(at 0 0 0)
			(layer "B.Fab")
			(effects
				(font
					(size 1.27 1.27)
				)
				(justify mirror)
			)
		)
		(duplicate_pad_numbers_are_jumpers no)
		(fp_line
			(start -0.7874 -0.4064)
			(end -0.7874 0.4064)
			(stroke
				(width 0.1524)
				(type default)
			)
			(layer "B.SilkS")
		)
		(fp_line
			(start -0.7874 0.4064)
			(end 0.7874 0.4064)
			(stroke
				(width 0.1524)
				(type default)
			)
			(layer "B.SilkS")
		)
		(fp_line
			(start 0.7874 -0.4064)
			(end -0.7874 -0.4064)
			(stroke
				(width 0.1524)
				(type default)
			)
			(layer "B.SilkS")
		)
		(fp_line
			(start 0.7874 0.4064)
			(end 0.7874 -0.4064)
			(stroke
				(width 0.1524)
				(type default)
			)
			(layer "B.SilkS")
		)
		(fp_line
			(start -0.67945 -0.3048)
			(end -0.67945 0.3048)
			(stroke
				(width 0.1)
				(type default)
			)
			(layer "B.Fab")
		)
		(fp_line
			(start -0.67945 0.3048)
			(end -0.120396 0.3048)
			(stroke
				(width 0.1)
				(type default)
			)
			(layer "B.Fab")
		)
		(fp_line
			(start -0.12065 -0.3048)
			(end -0.67945 -0.3048)
			(stroke
				(width 0.1)
				(type default)
			)
			(layer "B.Fab")
		)
		(fp_line
			(start -0.12065 -0.2794)
			(end -0.12065 -0.3048)
			(stroke
				(width 0.1)
				(type default)
			)
			(layer "B.Fab")
		)
		(fp_line
			(start -0.120396 0.2794)
			(end 0.12065 0.2794)
			(stroke
				(width 0.1)
				(type default)
			)
			(layer "B.Fab")
		)
		(fp_line
			(start -0.120396 0.3048)
			(end -0.120396 0.2794)
			(stroke
				(width 0.1)
				(type default)
			)
			(layer "B.Fab")
		)
		(fp_line
			(start 0.12065 -0.305054)
			(end 0.12065 -0.2794)
			(stroke
				(width 0.1)
				(type default)
			)
			(layer "B.Fab")
		)
		(fp_line
			(start 0.12065 -0.2794)
			(end -0.12065 -0.2794)
			(stroke
				(width 0.1)
				(type default)
			)
			(layer "B.Fab")
		)
		(fp_line
			(start 0.12065 0.2794)
			(end 0.12065 0.3048)
			(stroke
				(width 0.1)
				(type default)
			)
			(layer "B.Fab")
		)
		(fp_line
			(start 0.12065 0.3048)
			(end 0.67945 0.3048)
			(stroke
				(width 0.1)
				(type default)
			)
			(layer "B.Fab")
		)
		(fp_line
			(start 0.67945 -0.305054)
			(end 0.12065 -0.305054)
			(stroke
				(width 0.1)
				(type default)
			)
			(layer "B.Fab")
		)
		(fp_line
			(start 0.67945 0.3048)
			(end 0.67945 -0.305054)
			(stroke
				(width 0.1)
				(type default)
			)
			(layer "B.Fab")
		)
		(pad "1" smd circle
			(at 0.40005 0 180)
			(size 0 0)
			(layers "B.Cu" "B.Mask" "B.Paste")
			(net "PVDD11_S3_P1")
		)
		(pad "2" smd circle
			(at -0.40005 0 180)
			(size 0 0)
			(layers "B.Cu" "B.Mask" "B.Paste")
			(net "GND")
		)
	)
	(footprint ""
		(layer "B.Cu")
		(at 45.332396 -337.989672 -90)
		(property "Reference" "PC460_2"
			(at 0 0 90)
			(layer "B.SilkS")
			(hide yes)
			(effects
				(font
					(size 1.27 1.27)
				)
				(justify mirror)
			)
		)
		(property "Value" ""
			(at 0 0 90)
			(layer "B.Fab")
			(effects
				(font
					(size 1.27 1.27)
				)
				(justify mirror)
			)
		)
		(duplicate_pad_numbers_are_jumpers no)
		(fp_line
			(start -1.524 0.762)
			(end 1.524 0.762)
			(stroke
				(width 0.1524)
				(type default)
			)
			(layer "B.SilkS")
		)
		(fp_line
			(start 1.524 0.762)
			(end 1.524 -0.762)
			(stroke
				(width 0.1524)
				(type default)
			)
			(layer "B.SilkS")
		)
		(fp_line
			(start -1.524 -0.762)
			(end -1.524 0.762)
			(stroke
				(width 0.1524)
				(type default)
			)
			(layer "B.SilkS")
		)
		(fp_line
			(start 1.524 -0.762)
			(end -1.524 -0.762)
			(stroke
				(width 0.1524)
				(type default)
			)
			(layer "B.SilkS")
		)
		(fp_line
			(start -1.1049 0.724916)
			(end -1.1049 -0.724916)
			(stroke
				(width 0.1)
				(type default)
			)
			(layer "B.Fab")
		)
		(fp_line
			(start 1.1049 0.724916)
			(end -1.1049 0.724916)
			(stroke
				(width 0.1)
				(type default)
			)
			(layer "B.Fab")
		)
		(fp_line
			(start -1.1049 -0.724916)
			(end 1.1049 -0.724916)
			(stroke
				(width 0.1)
				(type default)
			)
			(layer "B.Fab")
		)
		(fp_line
			(start 1.1049 -0.724916)
			(end 1.1049 0.724916)
			(stroke
				(width 0.1)
				(type default)
			)
			(layer "B.Fab")
		)
		(pad "1" smd rect
			(at 0.889 0 270)
			(size 1.016 1.27)
			(layers "B.Cu" "B.Mask" "B.Paste")
			(net "PVDDIO_P1")
		)
		(pad "2" smd rect
			(at -0.889 0 270)
			(size 1.016 1.27)
			(layers "B.Cu" "B.Mask" "B.Paste")
			(net "GND")
		)
	)
	(footprint ""
		(layer "B.Cu")
		(at 12.720574 -373.339614 90)
		(property "Reference" "PC6626"
			(at -3.515614 -3.095244 270)
			(unlocked yes)
			(layer "B.SilkS")
			(effects
				(font
					(size 0.7874 0.5842)
					(thickness 0.1524)
				)
				(justify left mirror)
			)
		)
		(property "Value" ""
			(at 0 0 90)
			(layer "B.Fab")
			(effects
				(font
					(size 1.27 1.27)
				)
				(justify mirror)
			)
		)
		(duplicate_pad_numbers_are_jumpers no)
		(fp_line
			(start 4.84378 -2.150618)
			(end 4.53898 -2.150618)
			(stroke
				(width 0.1524)
				(type default)
			)
			(layer "B.SilkS")
		)
		(fp_line
			(start 4.84378 -2.150618)
			(end 4.842256 2.163064)
			(stroke
				(width 0.1524)
				(type default)
			)
			(layer "B.SilkS")
		)
		(fp_line
			(start 4.69138 -2.150618)
			(end 4.692396 2.161032)
			(stroke
				(width 0.1524)
				(type default)
			)
			(layer "B.SilkS")
		)
		(fp_line
			(start 4.53898 -2.150618)
			(end 4.539742 2.152142)
			(stroke
				(width 0.1524)
				(type default)
			)
			(layer "B.SilkS")
		)
		(fp_line
			(start 4.53898 -2.15011)
			(end -4.53898 -2.15011)
			(stroke
				(width 0.1524)
				(type default)
			)
			(layer "B.SilkS")
		)
		(fp_line
			(start -4.53898 -2.15011)
			(end -4.53898 2.15011)
			(stroke
				(width 0.1524)
				(type default)
			)
			(layer "B.SilkS")
		)
		(fp_line
			(start 4.53898 2.15011)
			(end 4.53898 -2.15011)
			(stroke
				(width 0.1524)
				(type default)
			)
			(layer "B.SilkS")
		)
		(fp_line
			(start -4.53898 2.15011)
			(end 4.53898 2.15011)
			(stroke
				(width 0.1524)
				(type default)
			)
			(layer "B.SilkS")
		)
		(fp_line
			(start 4.83108 2.150364)
			(end 4.447794 2.149348)
			(stroke
				(width 0.1524)
				(type default)
			)
			(layer "B.SilkS")
		)
		(fp_line
			(start 3.64998 -2.15011)
			(end -3.64998 -2.15011)
			(stroke
				(width 0.1)
				(type default)
			)
			(layer "B.Fab")
		)
		(fp_line
			(start -3.64998 -2.15011)
			(end -3.64998 2.15011)
			(stroke
				(width 0.1)
				(type default)
			)
			(layer "B.Fab")
		)
		(fp_line
			(start 3.64998 2.15011)
			(end 3.64998 -2.15011)
			(stroke
				(width 0.1)
				(type default)
			)
			(layer "B.Fab")
		)
		(fp_line
			(start -3.64998 2.15011)
			(end 3.64998 2.15011)
			(stroke
				(width 0.1)
				(type default)
			)
			(layer "B.Fab")
		)
		(fp_text user "+"
			(at 5.206746 -2.983484 90)
			(unlocked yes)
			(layer "B.SilkS")
			(effects
				(font
					(size 1.905 1.4224)
					(thickness 0.1524)
				)
				(justify left mirror)
			)
		)
		(fp_text user "-"
			(at -4.313174 -0.094488 90)
			(unlocked yes)
			(layer "B.SilkS")
			(effects
				(font
					(size 1.905 1.4224)
					(thickness 0.1524)
				)
				(justify left mirror)
			)
		)
		(fp_text user "+"
			(at 6.214872 -0.337058 90)
			(unlocked yes)
			(layer "B.Fab")
			(effects
				(font
					(size 1.905 1.4224)
					(thickness 0.1524)
				)
				(justify left mirror)
			)
		)
		(fp_text user "-"
			(at -4.313174 -0.094488 90)
			(unlocked yes)
			(layer "B.Fab")
			(effects
				(font
					(size 1.905 1.4224)
					(thickness 0.1524)
				)
				(justify left mirror)
			)
		)
		(pad "1" smd rect
			(at 3.199892 0 270)
			(size 2.413 2.8194)
			(layers "B.Cu" "B.Mask" "B.Paste")
			(net "P0V9_CPU1_RT_2D")
		)
		(pad "2" smd rect
			(at -3.199892 0 270)
			(size 2.413 2.8194)
			(layers "B.Cu" "B.Mask" "B.Paste")
			(net "GND")
		)
	)
	(footprint ""
		(layer "B.Cu")
		(at 183.769 -100.294948 -90)
		(property "Reference" "R959"
			(at 0 0 90)
			(layer "B.SilkS")
			(hide yes)
			(effects
				(font
					(size 1.27 1.27)
				)
				(justify mirror)
			)
		)
		(property "Value" ""
			(at 0 0 90)
			(layer "B.Fab")
			(effects
				(font
					(size 1.27 1.27)
				)
				(justify mirror)
			)
		)
		(duplicate_pad_numbers_are_jumpers no)
		(fp_line
			(start -0.7874 0.4064)
			(end 0.7874 0.4064)
			(stroke
				(width 0.1524)
				(type default)
			)
			(layer "B.SilkS")
		)
		(fp_line
			(start 0.7874 0.4064)
			(end 0.7874 -0.4064)
			(stroke
				(width 0.1524)
				(type default)
			)
			(layer "B.SilkS")
		)
		(fp_line
			(start -0.7874 -0.4064)
			(end -0.7874 0.4064)
			(stroke
				(width 0.1524)
				(type default)
			)
			(layer "B.SilkS")
		)
		(fp_line
			(start 0.7874 -0.4064)
			(end -0.7874 -0.4064)
			(stroke
				(width 0.1524)
				(type default)
			)
			(layer "B.SilkS")
		)
		(fp_line
			(start -0.67945 0.3048)
			(end -0.120396 0.3048)
			(stroke
				(width 0.1)
				(type default)
			)
			(layer "B.Fab")
		)
		(fp_line
			(start -0.120396 0.3048)
			(end -0.120396 0.2794)
			(stroke
				(width 0.1)
				(type default)
			)
			(layer "B.Fab")
		)
		(fp_line
			(start 0.12065 0.3048)
			(end 0.67945 0.3048)
			(stroke
				(width 0.1)
				(type default)
			)
			(layer "B.Fab")
		)
		(fp_line
			(start 0.67945 0.3048)
			(end 0.67945 -0.305054)
			(stroke
				(width 0.1)
				(type default)
			)
			(layer "B.Fab")
		)
		(fp_line
			(start -0.120396 0.2794)
			(end 0.12065 0.2794)
			(stroke
				(width 0.1)
				(type default)
			)
			(layer "B.Fab")
		)
		(fp_line
			(start 0.12065 0.2794)
			(end 0.12065 0.3048)
			(stroke
				(width 0.1)
				(type default)
			)
			(layer "B.Fab")
		)
		(fp_line
			(start -0.12065 -0.2794)
			(end -0.12065 -0.3048)
			(stroke
				(width 0.1)
				(type default)
			)
			(layer "B.Fab")
		)
		(fp_line
			(start 0.12065 -0.2794)
			(end -0.12065 -0.2794)
			(stroke
				(width 0.1)
				(type default)
			)
			(layer "B.Fab")
		)
		(fp_line
			(start -0.67945 -0.3048)
			(end -0.67945 0.3048)
			(stroke
				(width 0.1)
				(type default)
			)
			(layer "B.Fab")
		)
		(fp_line
			(start -0.12065 -0.3048)
			(end -0.67945 -0.3048)
			(stroke
				(width 0.1)
				(type default)
			)
			(layer "B.Fab")
		)
		(fp_line
			(start 0.12065 -0.305054)
			(end 0.12065 -0.2794)
			(stroke
				(width 0.1)
				(type default)
			)
			(layer "B.Fab")
		)
		(fp_line
			(start 0.67945 -0.305054)
			(end 0.12065 -0.305054)
			(stroke
				(width 0.1)
				(type default)
			)
			(layer "B.Fab")
		)
		(pad "1" smd circle
			(at 0.40005 0 90)
			(size 0 0)
			(layers "B.Cu" "B.Mask" "B.Paste")
			(net "OCP_SFF_MAIN_PWR_EN")
		)
		(pad "2" smd circle
			(at -0.40005 0 90)
			(size 0 0)
			(layers "B.Cu" "B.Mask" "B.Paste")
			(net "FM_PLD_OCP_SFF_MAIN_PWR_EN_R")
		)
	)
	(footprint ""
		(layer "B.Cu")
		(at 418.746178 -396.393162 -90)
		(property "Reference" "C804"
			(at 0 0 90)
			(layer "B.SilkS")
			(hide yes)
			(effects
				(font
					(size 1.27 1.27)
				)
				(justify mirror)
			)
		)
		(property "Value" ""
			(at 0 0 90)
			(layer "B.Fab")
			(effects
				(font
					(size 1.27 1.27)
				)
				(justify mirror)
			)
		)
		(duplicate_pad_numbers_are_jumpers no)
		(fp_line
			(start -0.299974 0.150114)
			(end 0.299974 0.150114)
			(stroke
				(width 0.1)
				(type default)
			)
			(layer "B.Fab")
		)
		(fp_line
			(start 0.299974 0.150114)
			(end 0.299974 -0.150114)
			(stroke
				(width 0.1)
				(type default)
			)
			(layer "B.Fab")
		)
		(fp_line
			(start -0.299974 -0.150114)
			(end -0.299974 0.150114)
			(stroke
				(width 0.1)
				(type default)
			)
			(layer "B.Fab")
		)
		(fp_line
			(start 0.299974 -0.150114)
			(end -0.299974 -0.150114)
			(stroke
				(width 0.1)
				(type default)
			)
			(layer "B.Fab")
		)
		(pad "1" smd rect
			(at 0.2667 0 90)
			(size 0.3048 0.381)
			(layers "B.Cu" "B.Mask" "B.Paste")
			(net "P0V9_CPU0_RT2_2A")
		)
		(pad "2" smd rect
			(at -0.2667 0 90)
			(size 0.3048 0.381)
			(layers "B.Cu" "B.Mask" "B.Paste")
			(net "GND")
		)
	)
)
